FILE_TYPE = CONNECTIVITY;
{Allegro Design Entry HDL 17.2-2016 S081 (4005846) 1/11/2022}
"PAGE_NUMBER" = 95;
0"NC";
1"M_K_CPU0_SA_CB<7:0>";
2"M_K_CPU0_SA_CA<6:0>";
3"M_K_CPU0_SB_CA<6:0>";
4"M_K_CPU0_SB_CB<7:0>";
5"M_K_CPU0_SA_DQ<31:0>";
6"M_K_CPU0_SB_DQ<31:0>";
7"M_K_CPU0_SA_DQS_DN<9:0>";
8"M_K_CPU0_SA_DQS_DP<9:0>";
9"M_K_CPU0_SB_DQS_DN<9:0>";
10"M_K_CPU0_SB_DQS_DP<9:0>";
11"GND\g";
12"GND\g";
13"P3V3_STBY\g";
14"I3C_SPD_DDRK_CPU0_SCL";
15"I3C_SPD_DDRGL_CPU0_SCL";
16"PWRGD_CHK_CPU0_DIMM";
17"TP_CHK_CPU0_DIMM_RFU_0";
18"TP_CHK_CPU0_DIMM_RFU_1";
19"TP_CHK_CPU0_DIMM_RFU_2";
20"TP_CHK_CPU0_DIMM_RFU_5";
21"I3C_SPD_DDRGL_CPU0_SDA";
22"TP_CHK_CPU0_DIMM_RFU_6";
23"TP_CHK_CPU0_DIMM_RFU_4";
24"TP_CHK_CPU0_DIMM_RFU_3";
25"PWRGD_CHGL_CPU0";
26"PD_CHK_CPU0_DIMM_SAA";
27"P3V3_STBY\g";
28"M_K_CPU0_SA_RSP<0>";
29"M_K_CPU0_ALERT_N";
30"M_K_CPU0_CLK_DN<0>";
31"M_K_CPU0_CLK_DP<0>";
32"M_K_CPU0_SB_RSP<0>";
33"M_K_CPU0_SA_CS_N<0>";
34"M_K_CPU0_SA_CS_N<1>";
35"M_K_CPU0_SA_CA<6>";
36"M_K_CPU0_SA_CA<5>";
37"M_K_CPU0_SA_CA<4>";
38"M_K_CPU0_SA_CA<3>";
39"GND\g";
40"P12V_MEM_0\g";
41"GND\g";
42"M_K_CPU0_SB_DQS_DP<9>";
43"M_K_CPU0_SB_DQS_DN<9>";
44"M_K_CPU0_SA_DQS_DP<9>";
45"M_K_CPU0_SA_DQS_DN<9>";
46"M_K_CPU0_SA_DQS_DP<8>";
47"M_K_CPU0_SA_DQS_DN<8>";
48"M_K_CPU0_SB_DQS_DN<7>";
49"M_K_CPU0_SA_DQS_DP<7>";
50"M_K_CPU0_SB_DQS_DP<6>";
51"M_K_CPU0_SB_DQS_DN<6>";
52"M_K_CPU0_SA_DQS_DN<6>";
53"M_K_CPU0_SB_DQS_DP<5>";
54"M_K_CPU0_SB_DQS_DN<5>";
55"M_K_CPU0_SA_DQS_DP<5>";
56"M_K_CPU0_SA_DQS_DN<5>";
57"M_K_CPU0_SB_DQS_DP<4>";
58"M_K_CPU0_SB_DQS_DN<4>";
59"M_K_CPU0_SA_DQS_DP<4>";
60"M_K_CPU0_SA_DQS_DN<4>";
61"M_K_CPU0_SB_DQS_DP<3>";
62"M_K_CPU0_SB_DQS_DN<3>";
63"M_K_CPU0_SA_DQS_DP<3>";
64"M_K_CPU0_SA_DQS_DN<3>";
65"M_K_CPU0_SB_DQS_DP<2>";
66"M_K_CPU0_SB_DQS_DN<2>";
67"M_K_CPU0_SA_DQS_DP<2>";
68"M_K_CPU0_SA_DQS_DN<2>";
69"M_K_CPU0_SB_DQS_DP<1>";
70"M_K_CPU0_SB_DQS_DN<1>";
71"M_K_CPU0_SA_DQS_DP<1>";
72"M_K_CPU0_SA_DQS_DN<1>";
73"M_K_CPU0_SB_DQS_DP<0>";
74"M_K_CPU0_SB_DQS_DN<0>";
75"M_K_CPU0_SA_DQS_DP<0>";
76"M_K_CPU0_SA_DQS_DN<0>";
77"M_K_CPU0_SB_DQS_DP<7>";
78"M_K_CPU0_SB_DQS_DN<8>";
79"M_K_CPU0_SB_DQS_DP<8>";
80"M_K_CPU0_SA_DQS_DP<6>";
81"M_K_CPU0_SA_DQS_DN<7>";
82"M_K_CPU0_RESET_N";
83"M_K_CPU0_SB_PAR";
84"M_K_CPU0_SA_PAR";
85"M_K_CPU0_SB_DQ<0>";
86"M_K_CPU0_SB_DQ<1>";
87"M_K_CPU0_SB_DQ<2>";
88"M_K_CPU0_SB_DQ<3>";
89"M_K_CPU0_SB_DQ<4>";
90"M_K_CPU0_SB_DQ<5>";
91"M_K_CPU0_SB_DQ<6>";
92"M_K_CPU0_SB_DQ<7>";
93"M_K_CPU0_SB_DQ<8>";
94"M_K_CPU0_SB_DQ<9>";
95"M_K_CPU0_SB_DQ<10>";
96"M_K_CPU0_SB_DQ<11>";
97"M_K_CPU0_SB_DQ<12>";
98"M_K_CPU0_SB_DQ<13>";
99"M_K_CPU0_SB_DQ<14>";
100"M_K_CPU0_SB_DQ<15>";
101"M_K_CPU0_SB_DQ<16>";
102"M_K_CPU0_SB_DQ<17>";
103"M_K_CPU0_SB_DQ<18>";
104"M_K_CPU0_SB_DQ<19>";
105"M_K_CPU0_SB_DQ<20>";
106"M_K_CPU0_SB_DQ<21>";
107"M_K_CPU0_SB_DQ<22>";
108"M_K_CPU0_SB_DQ<23>";
109"M_K_CPU0_SB_DQ<24>";
110"M_K_CPU0_SB_DQ<25>";
111"M_K_CPU0_SB_DQ<26>";
112"M_K_CPU0_SB_DQ<27>";
113"M_K_CPU0_SB_DQ<28>";
114"M_K_CPU0_SB_DQ<29>";
115"M_K_CPU0_SB_DQ<30>";
116"M_K_CPU0_SB_DQ<31>";
117"M_K_CPU0_SA_DQ<0>";
118"M_K_CPU0_SA_DQ<1>";
119"M_K_CPU0_SA_DQ<2>";
120"M_K_CPU0_SA_DQ<3>";
121"M_K_CPU0_SA_DQ<4>";
122"M_K_CPU0_SA_DQ<5>";
123"M_K_CPU0_SA_DQ<6>";
124"M_K_CPU0_SA_DQ<7>";
125"M_K_CPU0_SA_DQ<8>";
126"M_K_CPU0_SA_DQ<9>";
127"M_K_CPU0_SA_DQ<10>";
128"M_K_CPU0_SA_DQ<11>";
129"M_K_CPU0_SA_DQ<12>";
130"M_K_CPU0_SA_DQ<13>";
131"M_K_CPU0_SA_DQ<14>";
132"M_K_CPU0_SA_DQ<15>";
133"M_K_CPU0_SA_DQ<16>";
134"M_K_CPU0_SA_DQ<17>";
135"M_K_CPU0_SA_DQ<18>";
136"M_K_CPU0_SA_DQ<19>";
137"M_K_CPU0_SA_DQ<20>";
138"M_K_CPU0_SA_DQ<21>";
139"M_K_CPU0_SA_DQ<22>";
140"M_K_CPU0_SA_DQ<23>";
141"M_K_CPU0_SA_DQ<24>";
142"M_K_CPU0_SA_DQ<25>";
143"M_K_CPU0_SA_DQ<26>";
144"M_K_CPU0_SA_DQ<27>";
145"M_K_CPU0_SA_DQ<28>";
146"M_K_CPU0_SA_DQ<29>";
147"M_K_CPU0_SA_DQ<30>";
148"M_K_CPU0_SB_CS_N<1>";
149"M_K_CPU0_SB_CS_N<0>";
150"M_K_CPU0_SB_CB<0>";
151"M_K_CPU0_SB_CB<1>";
152"M_K_CPU0_SB_CB<2>";
153"M_K_CPU0_SB_CB<3>";
154"M_K_CPU0_SB_CB<4>";
155"M_K_CPU0_SB_CB<5>";
156"M_K_CPU0_SB_CB<6>";
157"M_K_CPU0_SA_CB<0>";
158"M_K_CPU0_SA_CB<2>";
159"M_K_CPU0_SA_CB<3>";
160"M_K_CPU0_SA_CB<5>";
161"M_K_CPU0_SA_CB<6>";
162"M_K_CPU0_SB_CA<6>";
163"M_K_CPU0_SB_CA<5>";
164"M_K_CPU0_SB_CA<4>";
165"M_K_CPU0_SB_CA<3>";
166"M_K_CPU0_SB_CA<2>";
167"M_K_CPU0_SA_CA<2>";
168"M_K_CPU0_SB_CA<1>";
169"M_K_CPU0_SA_CA<1>";
170"M_K_CPU0_SB_CA<0>";
171"M_K_CPU0_SA_CA<0>";
172"M_K_CPU0_SB_CB<7>";
173"M_K_CPU0_SA_CB<1>";
174"M_K_CPU0_SA_CB<4>";
175"M_K_CPU0_SA_CB<7>";
176"M_K_CPU0_SA_DQ<31>";
177"GND\g";
178"PD_CHK_CPU0_DIMM_SAA";
%"TAP"
"1","(-6025,4125)","0","mstr_standard","I100";
;
CDS_LIB"mstr_standard"
BODY_TYPE"PLUMBING"
HDL_TAP"TRUE";
"B \NAC \NWC"5;
"S \NAC"
BN"6"123;
%"TAP"
"1","(-6025,4175)","0","mstr_standard","I101";
;
CDS_LIB"mstr_standard"
BODY_TYPE"PLUMBING"
HDL_TAP"TRUE";
"B \NAC \NWC"5;
"S \NAC"
BN"7"124;
%"TAP"
"1","(-6025,4225)","0","mstr_standard","I102";
;
CDS_LIB"mstr_standard"
BODY_TYPE"PLUMBING"
HDL_TAP"TRUE";
"B \NAC \NWC"5;
"S \NAC"
BN"8"125;
%"TAP"
"1","(-6025,4275)","0","mstr_standard","I103";
;
CDS_LIB"mstr_standard"
BODY_TYPE"PLUMBING"
HDL_TAP"TRUE";
"B \NAC \NWC"5;
"S \NAC"
BN"9"126;
%"TAP"
"1","(-6025,4325)","0","mstr_standard","I104";
;
CDS_LIB"mstr_standard"
BODY_TYPE"PLUMBING"
HDL_TAP"TRUE";
"B \NAC \NWC"5;
"S \NAC"
BN"10"127;
%"TAP"
"1","(-6025,4425)","0","mstr_standard","I105";
;
CDS_LIB"mstr_standard"
BODY_TYPE"PLUMBING"
HDL_TAP"TRUE";
"B \NAC \NWC"5;
"S \NAC"
BN"12"129;
%"TAP"
"1","(-6025,4375)","0","mstr_standard","I106";
;
CDS_LIB"mstr_standard"
BODY_TYPE"PLUMBING"
HDL_TAP"TRUE";
"B \NAC \NWC"5;
"S \NAC"
BN"11"128;
%"TAP"
"1","(-6025,4475)","0","mstr_standard","I107";
;
CDS_LIB"mstr_standard"
BODY_TYPE"PLUMBING"
HDL_TAP"TRUE";
"B \NAC \NWC"5;
"S \NAC"
BN"13"130;
%"TAP"
"1","(-6025,4525)","0","mstr_standard","I108";
;
CDS_LIB"mstr_standard"
BODY_TYPE"PLUMBING"
HDL_TAP"TRUE";
"B \NAC \NWC"5;
"S \NAC"
BN"14"131;
%"TAP"
"1","(-6025,4575)","0","mstr_standard","I109";
;
CDS_LIB"mstr_standard"
BODY_TYPE"PLUMBING"
HDL_TAP"TRUE";
"B \NAC \NWC"5;
"S \NAC"
BN"15"132;
%"TAP"
"1","(-6025,4625)","0","mstr_standard","I110";
;
CDS_LIB"mstr_standard"
BODY_TYPE"PLUMBING"
HDL_TAP"TRUE";
"B \NAC \NWC"5;
"S \NAC"
BN"16"133;
%"TAP"
"1","(-6025,4675)","0","mstr_standard","I111";
;
CDS_LIB"mstr_standard"
BODY_TYPE"PLUMBING"
HDL_TAP"TRUE";
"B \NAC \NWC"5;
"S \NAC"
BN"17"134;
%"TAP"
"1","(-6025,4725)","0","mstr_standard","I112";
;
CDS_LIB"mstr_standard"
BODY_TYPE"PLUMBING"
HDL_TAP"TRUE";
"B \NAC \NWC"5;
"S \NAC"
BN"18"135;
%"TAP"
"1","(-6025,4775)","0","mstr_standard","I113";
;
CDS_LIB"mstr_standard"
BODY_TYPE"PLUMBING"
HDL_TAP"TRUE";
"B \NAC \NWC"5;
"S \NAC"
BN"19"136;
%"TAP"
"1","(-6025,4825)","0","mstr_standard","I114";
;
CDS_LIB"mstr_standard"
BODY_TYPE"PLUMBING"
HDL_TAP"TRUE";
"B \NAC \NWC"5;
"S \NAC"
BN"20"137;
%"TAP"
"1","(-6025,4875)","0","mstr_standard","I115";
;
CDS_LIB"mstr_standard"
BODY_TYPE"PLUMBING"
HDL_TAP"TRUE";
"B \NAC \NWC"5;
"S \NAC"
BN"21"138;
%"TAP"
"1","(-6025,4925)","0","mstr_standard","I116";
;
CDS_LIB"mstr_standard"
BODY_TYPE"PLUMBING"
HDL_TAP"TRUE";
"B \NAC \NWC"5;
"S \NAC"
BN"22"139;
%"TAP"
"1","(-6025,4975)","0","mstr_standard","I117";
;
CDS_LIB"mstr_standard"
BODY_TYPE"PLUMBING"
HDL_TAP"TRUE";
"B \NAC \NWC"5;
"S \NAC"
BN"23"140;
%"TAP"
"1","(-6025,5025)","0","mstr_standard","I118";
;
CDS_LIB"mstr_standard"
BODY_TYPE"PLUMBING"
HDL_TAP"TRUE";
"B \NAC \NWC"5;
"S \NAC"
BN"24"141;
%"TAP"
"1","(-6025,5075)","0","mstr_standard","I119";
;
CDS_LIB"mstr_standard"
BODY_TYPE"PLUMBING"
HDL_TAP"TRUE";
"B \NAC \NWC"5;
"S \NAC"
BN"25"142;
%"TAP"
"1","(-6025,5125)","0","mstr_standard","I120";
;
CDS_LIB"mstr_standard"
BODY_TYPE"PLUMBING"
HDL_TAP"TRUE";
"B \NAC \NWC"5;
"S \NAC"
BN"26"143;
%"TAP"
"1","(-6025,5175)","0","mstr_standard","I121";
;
CDS_LIB"mstr_standard"
BODY_TYPE"PLUMBING"
HDL_TAP"TRUE";
"B \NAC \NWC"5;
"S \NAC"
BN"27"144;
%"TAP"
"1","(-6025,5225)","0","mstr_standard","I122";
;
CDS_LIB"mstr_standard"
BODY_TYPE"PLUMBING"
HDL_TAP"TRUE";
"B \NAC \NWC"5;
"S \NAC"
BN"28"145;
%"TAP"
"1","(-6025,5325)","0","mstr_standard","I123";
;
CDS_LIB"mstr_standard"
BODY_TYPE"PLUMBING"
HDL_TAP"TRUE";
"B \NAC \NWC"5;
"S \NAC"
BN"30"147;
%"TAP"
"1","(-6025,5275)","0","mstr_standard","I124";
;
CDS_LIB"mstr_standard"
BODY_TYPE"PLUMBING"
HDL_TAP"TRUE";
"B \NAC \NWC"5;
"S \NAC"
BN"29"146;
%"TAP"
"1","(-6025,5375)","0","mstr_standard","I125";
;
CDS_LIB"mstr_standard"
BODY_TYPE"PLUMBING"
HDL_TAP"TRUE";
"B \NAC \NWC"5;
"S \NAC"
BN"31"176;
%"GND"
"1","(-6425,1050)","0","mstr_symbols","I128";
;
CDS_LIB"mstr_symbols"
BOM_COST"MEM"
SIZE"1B"
BODY_TYPE"PLUMBING"
VOLTAGE"0.0"
HDL_POWER"GND";
"A\NAC"11;
%"Q_RES"
"2","(-6425,1275)","0","pure_quanta","I129";
;
LOCATION"R768"
$SEC"1"
CDS_SEC"1"
WATTAGE"1/16W"
MATERIAL"CHIP"
TOLERANCE"1%"
VALUE"54.9K"
PART_NUMBER"TMP_QCS35492FB14"
PACK_TYPE"0402LF"
CDS_LIB"pure_quanta";
"A"
$PN"1"178;
"B"
$PN"2"11;
%"GND"
"1","(-2125,1900)","0","mstr_symbols","I130";
;
SIZE"1B"
CDS_LIB"mstr_symbols"
BODY_TYPE"PLUMBING"
VOLTAGE"0.0"
HDL_POWER"GND";
"A\NAC"41;
%"GND"
"1","(-325,1675)","0","mstr_symbols","I144";
;
SIZE"1B"
CDS_LIB"mstr_symbols"
BODY_TYPE"PLUMBING"
VOLTAGE"0.0"
HDL_POWER"GND";
"A\NAC"39;
%"SCONN288_DDR506112002KQ"
"3","(-1225,3675)","0","pure_quanta","I177";
;
LOCATION"J20"
$SEC"3"
CDS_SEC"3"
PART_TYPE"SMLF"
VALUE"SCONN288_DDR506112002KQ"
MATERIAL"IO"
PART_NUMBER"DFHST8FS479"
CDS_LMAN_SYM_OUTLINE"-450,1800,450,-1750"
NEEDS_NO_SIZE"TRUE"
CDS_LIB"pure_quanta";
"G3"
$PN"G3"39;
"G2"
$PN"G2"39;
"G1"
$PN"G1"39;
"VSS62"
$PN"141"39;
"VSS61"
$PN"139"39;
"VSS60"
$PN"136"39;
"VSS58"
$PN"132"39;
"VSS104"
$PN"240"41;
"VSS102"
$PN"235"41;
"VSS100"
$PN"230"41;
"VIN_BULK2"
$PN"146"40;
"VIN_BULK1"
$PN"145"40;
"VIN_BULK0"
$PN"1"40;
"VSS126"
$PN"288"41;
"VSS125"
$PN"286"41;
"VSS124"
$PN"284"41;
"VSS123"
$PN"281"41;
"VSS122"
$PN"279"41;
"VSS121"
$PN"277"41;
"VSS120"
$PN"275"41;
"VSS119"
$PN"273"41;
"VSS118"
$PN"270"41;
"VSS117"
$PN"268"41;
"VSS116"
$PN"266"41;
"VSS115"
$PN"264"41;
"VSS114"
$PN"262"41;
"VSS113"
$PN"259"41;
"VSS112"
$PN"257"41;
"VSS111"
$PN"255"41;
"VSS110"
$PN"253"41;
"VSS109"
$PN"251"41;
"VSS108"
$PN"248"41;
"VSS107"
$PN"246"41;
"VSS106"
$PN"244"41;
"VSS105"
$PN"242"41;
"VSS103"
$PN"237"41;
"VSS101"
$PN"233"41;
"VSS99"
$PN"228"41;
"VSS98"
$PN"226"41;
"VSS97"
$PN"224"41;
"VSS96"
$PN"222"41;
"VSS95"
$PN"219"41;
"VSS94"
$PN"216"41;
"VSS93"
$PN"214"41;
"VSS92"
$PN"212"41;
"VSS91"
$PN"210"41;
"VSS90"
$PN"208"41;
"VSS89"
$PN"206"41;
"VSS88"
$PN"204"41;
"VSS87"
$PN"202"41;
"VSS86"
$PN"199"41;
"VSS85"
$PN"197"41;
"VSS84"
$PN"195"41;
"VSS83"
$PN"193"41;
"VSS82"
$PN"191"41;
"VSS81"
$PN"188"41;
"VSS80"
$PN"186"41;
"VSS79"
$PN"184"41;
"VSS78"
$PN"182"41;
"VSS77"
$PN"180"41;
"VSS76"
$PN"177"41;
"VSS75"
$PN"175"41;
"VSS74"
$PN"173"41;
"VSS73"
$PN"171"41;
"VSS72"
$PN"169"41;
"VSS71"
$PN"166"41;
"VSS70"
$PN"164"41;
"VSS69"
$PN"162"41;
"VSS68"
$PN"160"41;
"VSS67"
$PN"158"41;
"VSS66"
$PN"155"41;
"VSS65"
$PN"153"41;
"VSS64"
$PN"151"41;
"VSS63"
$PN"143"39;
"VSS59"
$PN"134"39;
"VSS57"
$PN"130"39;
"VSS56"
$PN"128"39;
"VSS55"
$PN"125"39;
"VSS54"
$PN"123"39;
"VSS53"
$PN"121"39;
"VSS52"
$PN"119"39;
"VSS51"
$PN"117"39;
"VSS50"
$PN"114"39;
"VSS49"
$PN"112"39;
"VSS48"
$PN"110"39;
"VSS47"
$PN"108"39;
"VSS46"
$PN"106"39;
"VSS45"
$PN"103"39;
"VSS44"
$PN"101"39;
"VSS43"
$PN"99"39;
"VSS42"
$PN"97"39;
"VSS41"
$PN"95"39;
"VSS40"
$PN"92"39;
"VSS39"
$PN"90"39;
"VSS38"
$PN"88"39;
"VSS37"
$PN"85"39;
"VSS36"
$PN"83"39;
"VSS35"
$PN"81"39;
"VSS34"
$PN"79"39;
"VSS33"
$PN"77"39;
"VSS32"
$PN"75"39;
"VSS31"
$PN"73"39;
"VSS30"
$PN"71"39;
"VSS29"
$PN"69"39;
"VSS28"
$PN"67"39;
"VSS27"
$PN"65"39;
"VSS26"
$PN"63"39;
"VSS25"
$PN"61"39;
"VSS24"
$PN"59"39;
"VSS23"
$PN"57"39;
"VSS22"
$PN"54"39;
"VSS21"
$PN"52"39;
"VSS20"
$PN"50"39;
"VSS19"
$PN"48"39;
"VSS18"
$PN"46"39;
"VSS17"
$PN"43"39;
"VSS16"
$PN"41"39;
"VSS15"
$PN"39"39;
"VSS14"
$PN"37"39;
"VSS13"
$PN"35"39;
"VSS12"
$PN"32"39;
"VSS11"
$PN"30"39;
"VSS10"
$PN"28"39;
"VSS9"
$PN"26"39;
"VSS8"
$PN"24"39;
"VSS7"
$PN"21"39;
"VSS6"
$PN"19"39;
"VSS5"
$PN"17"39;
"VSS4"
$PN"15"39;
"VSS3"
$PN"13"39;
"VSS2"
$PN"10"39;
"VSS1"
$PN"8"39;
"VSS0"
$PN"6"39;
%"Q_CAP"
"1","(-8600,3200)","2","pure_quanta","I185";
;
LOCATION"C128"
$SEC"1"
CDS_SEC"1"
MATERIAL"X7R"
TOLERANCE"10%"
VALUE"0.1UF"
PART_NUMBER"CH4104K1B00"
VOLTAGE"25V"
PACK_TYPE"0402"
BOM_COST"MEM"
CDS_LIB"pure_quanta"
ROOM"MEM_CH_A_CPU0_DIMM1";
"B"
$PN"2"12;
"A"
$PN"1"27;
%"GND"
"1","(-8600,2975)","0","mstr_symbols","I186";
;
BOM_COST"MEM"
SIZE"1B"
CDS_LIB"mstr_symbols"
BODY_TYPE"PLUMBING"
VOLTAGE"0"
ROOM"MEM_EFGH_DECOUPLING_CAPS"
HDL_POWER"GND";
"A\NAC"12;
%"Q_RES"
"1","(-8475,2125)","2","pure_quanta","I188";
;
LOCATION"R301"
$SEC"1"
CDS_SEC"1"
VALUE"0"
CDS_LIB"pure_quanta"
BOM_COST"MEM"
WATTAGE"1/16W"
MATERIAL"CHIP"
TOLERANCE"5%"
PART_NUMBER"CS00002JB38"
PACK_TYPE"0402LF"
ROOM"RST_CPU0_PLD_TO_DIMM";
"B"
$PN"2"25;
"A"
$PN"1"16;
%"Q_RES"
"2","(-8350,2275)","0","pure_quanta","I189";
;
LOCATION"R100"
$SEC"1"
CDS_SEC"1"
TOLERANCE"5%"
VALUE"1K"
PACK_TYPE"0402LF"
MATERIAL"EMPTY"
WATTAGE"1/16W"
CDS_LIB"pure_quanta"
BOM_COST"MEM"
PART_NUMBER"TMP_QCS21002JB34"
ROOM"MEM_CH_A_CPU0_DIMM1";
"A"
$PN"1"13;
"B"
$PN"2"16;
%"VCC_CORE"
"1","(-8350,2450)","0","mstr_symbols","I190";
;
HDL_POWER"P3V3_STBY"
CDS_LIB"mstr_symbols"
VOLTAGE"3.3"
ROOM"PVCCINFAON_CPU0_CTRL";
"A"13;
%"TAP"
"1","(-3275,3200)","0","mstr_standard","I191";
;
CDS_LIB"mstr_standard"
BODY_TYPE"PLUMBING"
HDL_TAP"TRUE";
"B \NAC \NWC"9;
"S \NAC"
BN"6"51;
%"TAP"
"1","(-3475,3250)","0","mstr_standard","I192";
;
CDS_LIB"mstr_standard"
BODY_TYPE"PLUMBING"
HDL_TAP"TRUE";
"B \NAC \NWC"10;
"S \NAC"
BN"6"50;
%"TAP"
"1","(-3475,3350)","0","mstr_standard","I193";
;
CDS_LIB"mstr_standard"
BODY_TYPE"PLUMBING"
HDL_TAP"TRUE";
"B \NAC \NWC"10;
"S \NAC"
BN"7"77;
%"TAP"
"1","(-3275,4550)","0","mstr_standard","I199";
;
CDS_LIB"mstr_standard"
BODY_TYPE"PLUMBING"
HDL_TAP"TRUE";
"B \NAC \NWC"7;
"S \NAC"
BN"9"45;
%"TAP"
"1","(-3275,4450)","0","mstr_standard","I200";
;
CDS_LIB"mstr_standard"
BODY_TYPE"PLUMBING"
HDL_TAP"TRUE";
"B \NAC \NWC"7;
"S \NAC"
BN"8"47;
%"TAP"
"1","(-3475,4600)","0","mstr_standard","I201";
;
CDS_LIB"mstr_standard"
BODY_TYPE"PLUMBING"
HDL_TAP"TRUE";
"B \NAC \NWC"8;
"S \NAC"
BN"9"44;
%"TAP"
"1","(-3475,4400)","0","mstr_standard","I202";
;
CDS_LIB"mstr_standard"
BODY_TYPE"PLUMBING"
HDL_TAP"TRUE";
"B \NAC \NWC"8;
"S \NAC"
BN"7"49;
%"TAP"
"1","(-3475,4500)","0","mstr_standard","I203";
;
CDS_LIB"mstr_standard"
BODY_TYPE"PLUMBING"
HDL_TAP"TRUE";
"B \NAC \NWC"8;
"S \NAC"
BN"8"46;
%"TAP"
"1","(-3275,4350)","0","mstr_standard","I204";
;
CDS_LIB"mstr_standard"
BODY_TYPE"PLUMBING"
HDL_TAP"TRUE";
"B \NAC \NWC"7;
"S \NAC"
BN"7"81;
%"TAP"
"1","(-3275,4150)","0","mstr_standard","I205";
;
CDS_LIB"mstr_standard"
BODY_TYPE"PLUMBING"
HDL_TAP"TRUE";
"B \NAC \NWC"7;
"S \NAC"
BN"5"56;
%"TAP"
"1","(-3275,4250)","0","mstr_standard","I206";
;
CDS_LIB"mstr_standard"
BODY_TYPE"PLUMBING"
HDL_TAP"TRUE";
"B \NAC \NWC"7;
"S \NAC"
BN"6"52;
%"TAP"
"1","(-3275,4050)","0","mstr_standard","I207";
;
CDS_LIB"mstr_standard"
BODY_TYPE"PLUMBING"
HDL_TAP"TRUE";
"B \NAC \NWC"7;
"S \NAC"
BN"4"60;
%"TAP"
"1","(-3275,3950)","0","mstr_standard","I208";
;
CDS_LIB"mstr_standard"
BODY_TYPE"PLUMBING"
HDL_TAP"TRUE";
"B \NAC \NWC"7;
"S \NAC"
BN"3"64;
%"TAP"
"1","(-3275,3850)","0","mstr_standard","I209";
;
CDS_LIB"mstr_standard"
BODY_TYPE"PLUMBING"
HDL_TAP"TRUE";
"B \NAC \NWC"7;
"S \NAC"
BN"2"68;
%"TAP"
"1","(-3275,3650)","0","mstr_standard","I210";
;
CDS_LIB"mstr_standard"
BODY_TYPE"PLUMBING"
HDL_TAP"TRUE";
"B \NAC \NWC"7;
"S \NAC"
BN"0"76;
%"TAP"
"1","(-3275,3750)","0","mstr_standard","I211";
;
CDS_LIB"mstr_standard"
BODY_TYPE"PLUMBING"
HDL_TAP"TRUE";
"B \NAC \NWC"7;
"S \NAC"
BN"1"72;
%"TAP"
"1","(-3275,3500)","0","mstr_standard","I212";
;
CDS_LIB"mstr_standard"
BODY_TYPE"PLUMBING"
HDL_TAP"TRUE";
"B \NAC \NWC"9;
"S \NAC"
BN"9"43;
%"TAP"
"1","(-3275,3400)","0","mstr_standard","I213";
;
CDS_LIB"mstr_standard"
BODY_TYPE"PLUMBING"
HDL_TAP"TRUE";
"B \NAC \NWC"9;
"S \NAC"
BN"8"78;
%"TAP"
"1","(-3475,4300)","0","mstr_standard","I214";
;
CDS_LIB"mstr_standard"
BODY_TYPE"PLUMBING"
HDL_TAP"TRUE";
"B \NAC \NWC"8;
"S \NAC"
BN"6"80;
%"TAP"
"1","(-3475,4200)","0","mstr_standard","I215";
;
CDS_LIB"mstr_standard"
BODY_TYPE"PLUMBING"
HDL_TAP"TRUE";
"B \NAC \NWC"8;
"S \NAC"
BN"5"55;
%"TAP"
"1","(-3475,4100)","0","mstr_standard","I216";
;
CDS_LIB"mstr_standard"
BODY_TYPE"PLUMBING"
HDL_TAP"TRUE";
"B \NAC \NWC"8;
"S \NAC"
BN"4"59;
%"TAP"
"1","(-3475,3900)","0","mstr_standard","I217";
;
CDS_LIB"mstr_standard"
BODY_TYPE"PLUMBING"
HDL_TAP"TRUE";
"B \NAC \NWC"8;
"S \NAC"
BN"2"67;
%"TAP"
"1","(-3475,4000)","0","mstr_standard","I218";
;
CDS_LIB"mstr_standard"
BODY_TYPE"PLUMBING"
HDL_TAP"TRUE";
"B \NAC \NWC"8;
"S \NAC"
BN"3"63;
%"TAP"
"1","(-3475,3800)","0","mstr_standard","I219";
;
CDS_LIB"mstr_standard"
BODY_TYPE"PLUMBING"
HDL_TAP"TRUE";
"B \NAC \NWC"8;
"S \NAC"
BN"1"71;
%"SCONN288_DDR506112002KQ"
"1","(-6875,3625)","0","pure_quanta","I22";
;
LOCATION"J20"
$SEC"1"
CDS_SEC"1"
PART_TYPE"SMLF"
VALUE"SCONN288_DDR506112002KQ"
MATERIAL"IO"
PART_NUMBER"DFHST8FS479"
CDS_LMAN_SYM_OUTLINE"-450,1900,450,-1850"
NEEDS_NO_SIZE"TRUE"
CDS_LIB"pure_quanta";
"PWR_GOOD||FAIL_N"
$PN"147"16;
"DQ31_A"
$PN"194"176;
"CB7_A"
$PN"205"175;
"CB4_A"
$PN"58"174;
"CB1_A"
$PN"53"173;
"CB7_B"
$PN"236"172;
"ALERT_N \B"
$PN"62"29;
"CA0_A"
$PN"66"171;
"CA0_B"
$PN"76"170;
"CA1_A"
$PN"211"169;
"CA1_B"
$PN"221"168;
"CA2_A"
$PN"68"167;
"CA2_B"
$PN"78"166;
"CA3_A"
$PN"213"38;
"CA3_B"
$PN"223"165;
"CA4_A"
$PN"70"37;
"CA4_B"
$PN"80"164;
"CA5_A"
$PN"215"36;
"CA5_B"
$PN"225"163;
"CA6_A"
$PN"72"35;
"CA6_B"
$PN"82"162;
"CB6_A"
$PN"203"161;
"CB5_A"
$PN"60"160;
"CB3_A"
$PN"198"159;
"CB2_A"
$PN"196"158;
"CB0_A"
$PN"51"157;
"CB6_B"
$PN"234"156;
"CB5_B"
$PN"91"155;
"CB4_B"
$PN"89"154;
"CB3_B"
$PN"243"153;
"CB2_B"
$PN"241"152;
"CB1_B"
$PN"98"151;
"CB0_B"
$PN"96"150;
"CK_C \B"
$PN"218"30;
"CK_T"
$PN"217"31;
"CS0_A_N"
$PN"64"33;
"CS0_B_N"
$PN"84"149;
"CS1_A_N"
$PN"209"34;
"CS1_B_N"
$PN"229"148;
"DQ30_A"
$PN"192"147;
"DQ29_A"
$PN"49"146;
"DQ28_A"
$PN"47"145;
"DQ27_A"
$PN"187"144;
"DQ26_A"
$PN"185"143;
"DQ25_A"
$PN"42"142;
"DQ24_A"
$PN"40"141;
"DQ23_A"
$PN"183"140;
"DQ22_A"
$PN"181"139;
"DQ21_A"
$PN"38"138;
"DQ20_A"
$PN"36"137;
"DQ19_A"
$PN"176"136;
"DQ18_A"
$PN"174"135;
"DQ17_A"
$PN"31"134;
"DQ16_A"
$PN"29"133;
"DQ15_A"
$PN"172"132;
"DQ14_A"
$PN"170"131;
"DQ13_A"
$PN"27"130;
"DQ12_A"
$PN"25"129;
"DQ11_A"
$PN"165"128;
"DQ10_A"
$PN"163"127;
"DQ9_A"
$PN"20"126;
"DQ8_A"
$PN"18"125;
"DQ7_A"
$PN"161"124;
"DQ6_A"
$PN"159"123;
"DQ5_A"
$PN"16"122;
"DQ4_A"
$PN"14"121;
"DQ3_A"
$PN"154"120;
"DQ2_A"
$PN"152"119;
"DQ1_A"
$PN"9"118;
"DQ0_A"
$PN"7"117;
"DQ31_B"
$PN"287"116;
"DQ30_B"
$PN"285"115;
"DQ29_B"
$PN"142"114;
"DQ28_B"
$PN"140"113;
"DQ27_B"
$PN"280"112;
"DQ26_B"
$PN"278"111;
"DQ25_B"
$PN"135"110;
"DQ24_B"
$PN"133"109;
"DQ23_B"
$PN"276"108;
"DQ22_B"
$PN"274"107;
"DQ21_B"
$PN"131"106;
"DQ20_B"
$PN"129"105;
"DQ19_B"
$PN"269"104;
"DQ18_B"
$PN"267"103;
"DQ17_B"
$PN"124"102;
"DQ16_B"
$PN"122"101;
"DQ15_B"
$PN"265"100;
"DQ14_B"
$PN"263"99;
"DQ13_B"
$PN"120"98;
"DQ12_B"
$PN"118"97;
"DQ11_B"
$PN"258"96;
"DQ10_B"
$PN"256"95;
"DQ9_B"
$PN"113"94;
"DQ8_B"
$PN"111"93;
"DQ7_B"
$PN"254"92;
"DQ6_B"
$PN"252"91;
"DQ5_B"
$PN"109"90;
"DQ4_B"
$PN"107"89;
"DQ3_B"
$PN"247"88;
"DQ2_B"
$PN"245"87;
"DQ1_B"
$PN"102"86;
"DQ0_B"
$PN"100"85;
"HAS"
$PN"148"26;
"HSCL"
$PN"4"14;
"HSDA"
$PN"5"21;
"LBD||RSP_A_N"
$PN"86"28;
"LBS||RSP_B_N"
$PN"87"32;
"PAR_A"
$PN"74"84;
"PAR_B"
$PN"227"83;
"RESET_N \B"
$PN"207"82;
"RFU6"
$PN"232"22;
"RFU5"
$PN"231"20;
"RFU4"
$PN"220"23;
"RFU3"
$PN"150"24;
"RFU2"
$PN"149"19;
"RFU1"
$PN"144"18;
"RFU0"
$PN"2"17;
"VIN_MGMT"
$PN"3"27;
%"TAP"
"1","(-3475,3700)","0","mstr_standard","I220";
;
CDS_LIB"mstr_standard"
BODY_TYPE"PLUMBING"
HDL_TAP"TRUE";
"B \NAC \NWC"8;
"S \NAC"
BN"0"75;
%"TAP"
"1","(-3475,3550)","0","mstr_standard","I221";
;
CDS_LIB"mstr_standard"
BODY_TYPE"PLUMBING"
HDL_TAP"TRUE";
"B \NAC \NWC"10;
"S \NAC"
BN"9"42;
%"TAP"
"1","(-3475,3450)","0","mstr_standard","I222";
;
CDS_LIB"mstr_standard"
BODY_TYPE"PLUMBING"
HDL_TAP"TRUE";
"B \NAC \NWC"10;
"S \NAC"
BN"8"79;
%"TAP"
"1","(-3275,3300)","0","mstr_standard","I223";
;
CDS_LIB"mstr_standard"
BODY_TYPE"PLUMBING"
HDL_TAP"TRUE";
"B \NAC \NWC"9;
"S \NAC"
BN"7"48;
%"TAP"
"1","(-3275,3000)","0","mstr_standard","I224";
;
CDS_LIB"mstr_standard"
BODY_TYPE"PLUMBING"
HDL_TAP"TRUE";
"B \NAC \NWC"9;
"S \NAC"
BN"4"58;
%"TAP"
"1","(-3275,3100)","0","mstr_standard","I225";
;
CDS_LIB"mstr_standard"
BODY_TYPE"PLUMBING"
HDL_TAP"TRUE";
"B \NAC \NWC"9;
"S \NAC"
BN"5"54;
%"TAP"
"1","(-3275,2900)","0","mstr_standard","I226";
;
CDS_LIB"mstr_standard"
BODY_TYPE"PLUMBING"
HDL_TAP"TRUE";
"B \NAC \NWC"9;
"S \NAC"
BN"3"62;
%"TAP"
"1","(-3275,2800)","0","mstr_standard","I227";
;
CDS_LIB"mstr_standard"
BODY_TYPE"PLUMBING"
HDL_TAP"TRUE";
"B \NAC \NWC"9;
"S \NAC"
BN"2"66;
%"TAP"
"1","(-3275,2700)","0","mstr_standard","I228";
;
CDS_LIB"mstr_standard"
BODY_TYPE"PLUMBING"
HDL_TAP"TRUE";
"B \NAC \NWC"9;
"S \NAC"
BN"1"70;
%"TAP"
"1","(-3275,2600)","0","mstr_standard","I229";
;
CDS_LIB"mstr_standard"
BODY_TYPE"PLUMBING"
HDL_TAP"TRUE";
"B \NAC \NWC"9;
"S \NAC"
BN"0"74;
%"TAP"
"1","(-7725,3175)","2","mstr_standard","I23";
;
CDS_LIB"mstr_standard"
BODY_TYPE"PLUMBING"
HDL_TAP"TRUE";
"B \NAC \NWC"4;
"S \NAC"
BN"0"150;
%"TAP"
"1","(-3475,3150)","0","mstr_standard","I230";
;
CDS_LIB"mstr_standard"
BODY_TYPE"PLUMBING"
HDL_TAP"TRUE";
"B \NAC \NWC"10;
"S \NAC"
BN"5"53;
%"TAP"
"1","(-3475,3050)","0","mstr_standard","I231";
;
CDS_LIB"mstr_standard"
BODY_TYPE"PLUMBING"
HDL_TAP"TRUE";
"B \NAC \NWC"10;
"S \NAC"
BN"4"57;
%"TAP"
"1","(-3475,2950)","0","mstr_standard","I232";
;
CDS_LIB"mstr_standard"
BODY_TYPE"PLUMBING"
HDL_TAP"TRUE";
"B \NAC \NWC"10;
"S \NAC"
BN"3"61;
%"TAP"
"1","(-3475,2850)","0","mstr_standard","I233";
;
CDS_LIB"mstr_standard"
BODY_TYPE"PLUMBING"
HDL_TAP"TRUE";
"B \NAC \NWC"10;
"S \NAC"
BN"2"65;
%"TAP"
"1","(-3475,2750)","0","mstr_standard","I234";
;
CDS_LIB"mstr_standard"
BODY_TYPE"PLUMBING"
HDL_TAP"TRUE";
"B \NAC \NWC"10;
"S \NAC"
BN"1"69;
%"TAP"
"1","(-3475,2650)","0","mstr_standard","I235";
;
CDS_LIB"mstr_standard"
BODY_TYPE"PLUMBING"
HDL_TAP"TRUE";
"B \NAC \NWC"10;
"S \NAC"
BN"0"73;
%"SCONN288_DDR506112002KQ"
"2","(-4425,3600)","0","pure_quanta","I236";
;
LOCATION"J20"
$SEC"2"
CDS_SEC"2"
PART_TYPE"SMLF"
VALUE"SCONN288_DDR506112002KQ"
MATERIAL"IO"
PART_NUMBER"DFHST8FS479"
CDS_LMAN_SYM_OUTLINE"-600,1150,600,-1150"
NEEDS_NO_SIZE"TRUE"
CDS_LIB"pure_quanta";
"DQS7_A_C||TDQS7_A_C \B"
$PN"178"81;
"DQS6_A_T||TDQS6_A_T"
$PN"168"80;
"DQS8_B_T||TDQS8_B_T"
$PN"283"79;
"DQS8_B_C||TDQS8_B_C \B"
$PN"282"78;
"DQS7_B_T||TDQS7_B_T"
$PN"272"77;
"DQS0_A_C \B"
$PN"12"76;
"DQS0_A_T"
$PN"11"75;
"DQS0_B_C \B"
$PN"105"74;
"DQS0_B_T"
$PN"104"73;
"DQS1_A_C \B"
$PN"23"72;
"DQS1_A_T"
$PN"22"71;
"DQS1_B_C \B"
$PN"116"70;
"DQS1_B_T"
$PN"115"69;
"DQS2_A_C \B"
$PN"34"68;
"DQS2_A_T"
$PN"33"67;
"DQS2_B_C \B"
$PN"127"66;
"DQS2_B_T"
$PN"126"65;
"DQS3_A_C \B"
$PN"45"64;
"DQS3_A_T"
$PN"44"63;
"DQS3_B_C \B"
$PN"138"62;
"DQS3_B_T"
$PN"137"61;
"DQS4_A_C \B"
$PN"56"60;
"DQS4_A_T"
$PN"55"59;
"DQS4_B_C \B"
$PN"238"58;
"DQS4_B_T"
$PN"239"57;
"DQS5_A_C||TDQS5_A_C||DQS5_A_T||TDQS5_A_T \B"
$PN"156"56;
"DQS5_A_T||TDQS5_A_T"
$PN"157"55;
"DQS5_B_C||TDQS5_B_C \B"
$PN"249"54;
"DQS5_B_T||TDQS5_B_T"
$PN"250"53;
"DQS6_A_C||TDQS6_A_C||DQS6_A_T||TDQS6_A_T \B"
$PN"167"52;
"DQS6_B_C||TDQS6_B_C \B"
$PN"260"51;
"DQS6_B_T||TDQS6_B_T"
$PN"261"50;
"DQS7_A_T||TDQS7_A_T"
$PN"179"49;
"DQS7_B_C||TDQS7_B_C \B"
$PN"271"48;
"DQS8_A_C||TDQS8_A_C \B"
$PN"189"47;
"DQS8_A_T||TDQS8_A_T"
$PN"190"46;
"DQS9_A_C||TDQS9_A_C \B"
$PN"200"45;
"DQS9_A_T||TDQS9_A_T"
$PN"201"44;
"DQS9_B_C||TDQS9_B_C \B"
$PN"94"43;
"DQS9_B_T||TDQS9_B_T||DBI4_B_N"
$PN"93"42;
%"GND"
"1","(-2825,5650)","0","pure_quanta_power","I237";
;
CDS_LIB"pure_quanta_power"
BOM_COST"MEM"
SIZE"1B"
ROOM"MEM_EFGH_DECOUPLING_CAPS"
HDL_POWER"GND";
"A<SIZE-1..0>\NAC"177;
%"Q_CAP"
"1","(-2825,6000)","2","pure_quanta","I238";
;
LOCATION"C167"
$SEC"1"
CDS_SEC"1"
MATERIAL"X6S"
TOLERANCE"10%"
VALUE"10UF"
PART_NUMBER"CH6104KEA00"
VOLTAGE"25V"
PACK_TYPE"C0805"
BOM_COST"MEM"
CDS_LIB"pure_quanta"
ROOM"MEM_CH_A_CPU0_DIMM1";
"B"
$PN"2"177;
"A"
$PN"1"40;
%"Q_CAP"
"1","(-2250,6000)","2","pure_quanta","I239";
;
LOCATION"C169"
$SEC"1"
CDS_SEC"1"
MATERIAL"X6S"
TOLERANCE"10%"
VALUE"10UF"
PART_NUMBER"CH6104KEA00"
VOLTAGE"25V"
PACK_TYPE"C0805"
BOM_COST"MEM"
CDS_LIB"pure_quanta"
ROOM"MEM_CH_A_CPU0_DIMM1";
"B"
$PN"2"177;
"A"
$PN"1"40;
%"TAP"
"1","(-7725,3225)","2","mstr_standard","I24";
;
CDS_LIB"mstr_standard"
BODY_TYPE"PLUMBING"
HDL_TAP"TRUE";
"B \NAC \NWC"4;
"S \NAC"
BN"1"151;
%"UNIVERSAL_POWER"
"1","(-2825,6325)","0","pure_quanta_power","I240";
;
HDL_POWER"P12V_MEM_0"
BOM_COST"VR_SYSTEM"
CDS_LIB"pure_quanta_power";
"A"40;
%"Q_RES"
"1","(-7775,2675)","0","pure_quanta","I242";
;
$LOCATION"R1578"
CDS_LOCATION"R1578"
$SEC"1"
CDS_SEC"1"
VALUE"49.9"
CDS_LIB"pure_quanta"
PART_NUMBER"CS04992FB07"
TOLERANCE"1%"
WATTAGE"1/16W"
PACK_TYPE"0402LF"
MATERIAL"CHIP";
"B"
$PN"2"14;
"A"
$PN"1"15;
%"TAP"
"1","(-7725,3275)","2","mstr_standard","I25";
;
CDS_LIB"mstr_standard"
BODY_TYPE"PLUMBING"
HDL_TAP"TRUE";
"B \NAC \NWC"4;
"S \NAC"
BN"2"152;
%"TAP"
"1","(-7725,3375)","2","mstr_standard","I26";
;
CDS_LIB"mstr_standard"
BODY_TYPE"PLUMBING"
HDL_TAP"TRUE";
"B \NAC \NWC"4;
"S \NAC"
BN"4"154;
%"TAP"
"1","(-7725,3325)","2","mstr_standard","I27";
;
CDS_LIB"mstr_standard"
BODY_TYPE"PLUMBING"
HDL_TAP"TRUE";
"B \NAC \NWC"4;
"S \NAC"
BN"3"153;
%"TAP"
"1","(-7725,3425)","2","mstr_standard","I28";
;
CDS_LIB"mstr_standard"
BODY_TYPE"PLUMBING"
HDL_TAP"TRUE";
"B \NAC \NWC"4;
"S \NAC"
BN"5"155;
%"TAP"
"1","(-7725,3475)","2","mstr_standard","I29";
;
CDS_LIB"mstr_standard"
BODY_TYPE"PLUMBING"
HDL_TAP"TRUE";
"B \NAC \NWC"4;
"S \NAC"
BN"6"156;
%"TAP"
"1","(-7725,3525)","2","mstr_standard","I30";
;
CDS_LIB"mstr_standard"
BODY_TYPE"PLUMBING"
HDL_TAP"TRUE";
"B \NAC \NWC"4;
"S \NAC"
BN"7"172;
%"TAP"
"1","(-7725,3625)","2","mstr_standard","I31";
;
CDS_LIB"mstr_standard"
BODY_TYPE"PLUMBING"
HDL_TAP"TRUE";
"B \NAC \NWC"1;
"S \NAC"
BN"0"157;
%"TAP"
"1","(-7725,3675)","2","mstr_standard","I32";
;
CDS_LIB"mstr_standard"
BODY_TYPE"PLUMBING"
HDL_TAP"TRUE";
"B \NAC \NWC"1;
"S \NAC"
BN"1"173;
%"TAP"
"1","(-7725,3725)","2","mstr_standard","I33";
;
CDS_LIB"mstr_standard"
BODY_TYPE"PLUMBING"
HDL_TAP"TRUE";
"B \NAC \NWC"1;
"S \NAC"
BN"2"158;
%"TAP"
"1","(-7725,3775)","2","mstr_standard","I34";
;
CDS_LIB"mstr_standard"
BODY_TYPE"PLUMBING"
HDL_TAP"TRUE";
"B \NAC \NWC"1;
"S \NAC"
BN"3"159;
%"TAP"
"1","(-7725,3875)","2","mstr_standard","I35";
;
CDS_LIB"mstr_standard"
BODY_TYPE"PLUMBING"
HDL_TAP"TRUE";
"B \NAC \NWC"1;
"S \NAC"
BN"5"160;
%"TAP"
"1","(-7725,3825)","2","mstr_standard","I36";
;
CDS_LIB"mstr_standard"
BODY_TYPE"PLUMBING"
HDL_TAP"TRUE";
"B \NAC \NWC"1;
"S \NAC"
BN"4"174;
%"TAP"
"1","(-6025,2175)","0","mstr_standard","I37";
;
CDS_LIB"mstr_standard"
BODY_TYPE"PLUMBING"
HDL_TAP"TRUE";
"B \NAC \NWC"6;
"S \NAC"
BN"0"85;
%"TAP"
"1","(-6025,2225)","0","mstr_standard","I38";
;
CDS_LIB"mstr_standard"
BODY_TYPE"PLUMBING"
HDL_TAP"TRUE";
"B \NAC \NWC"6;
"S \NAC"
BN"1"86;
%"TAP"
"1","(-6025,2275)","0","mstr_standard","I39";
;
CDS_LIB"mstr_standard"
BODY_TYPE"PLUMBING"
HDL_TAP"TRUE";
"B \NAC \NWC"6;
"S \NAC"
BN"2"87;
%"TAP"
"1","(-6025,2325)","0","mstr_standard","I40";
;
CDS_LIB"mstr_standard"
BODY_TYPE"PLUMBING"
HDL_TAP"TRUE";
"B \NAC \NWC"6;
"S \NAC"
BN"3"88;
%"TAP"
"1","(-6025,2375)","0","mstr_standard","I41";
;
CDS_LIB"mstr_standard"
BODY_TYPE"PLUMBING"
HDL_TAP"TRUE";
"B \NAC \NWC"6;
"S \NAC"
BN"4"89;
%"TAP"
"1","(-6025,2475)","0","mstr_standard","I42";
;
CDS_LIB"mstr_standard"
BODY_TYPE"PLUMBING"
HDL_TAP"TRUE";
"B \NAC \NWC"6;
"S \NAC"
BN"6"91;
%"TAP"
"1","(-6025,2425)","0","mstr_standard","I43";
;
CDS_LIB"mstr_standard"
BODY_TYPE"PLUMBING"
HDL_TAP"TRUE";
"B \NAC \NWC"6;
"S \NAC"
BN"5"90;
%"TAP"
"1","(-6025,2575)","0","mstr_standard","I44";
;
CDS_LIB"mstr_standard"
BODY_TYPE"PLUMBING"
HDL_TAP"TRUE";
"B \NAC \NWC"6;
"S \NAC"
BN"8"93;
%"TAP"
"1","(-6025,2525)","0","mstr_standard","I45";
;
CDS_LIB"mstr_standard"
BODY_TYPE"PLUMBING"
HDL_TAP"TRUE";
"B \NAC \NWC"6;
"S \NAC"
BN"7"92;
%"TAP"
"1","(-6025,2625)","0","mstr_standard","I46";
;
CDS_LIB"mstr_standard"
BODY_TYPE"PLUMBING"
HDL_TAP"TRUE";
"B \NAC \NWC"6;
"S \NAC"
BN"9"94;
%"TAP"
"1","(-6025,2725)","0","mstr_standard","I47";
;
CDS_LIB"mstr_standard"
BODY_TYPE"PLUMBING"
HDL_TAP"TRUE";
"B \NAC \NWC"6;
"S \NAC"
BN"11"96;
%"TAP"
"1","(-6025,2675)","0","mstr_standard","I48";
;
CDS_LIB"mstr_standard"
BODY_TYPE"PLUMBING"
HDL_TAP"TRUE";
"B \NAC \NWC"6;
"S \NAC"
BN"10"95;
%"TAP"
"1","(-6025,2775)","0","mstr_standard","I49";
;
CDS_LIB"mstr_standard"
BODY_TYPE"PLUMBING"
HDL_TAP"TRUE";
"B \NAC \NWC"6;
"S \NAC"
BN"12"97;
%"TAP"
"1","(-6025,2825)","0","mstr_standard","I50";
;
CDS_LIB"mstr_standard"
BODY_TYPE"PLUMBING"
HDL_TAP"TRUE";
"B \NAC \NWC"6;
"S \NAC"
BN"13"98;
%"TAP"
"1","(-6025,2875)","0","mstr_standard","I51";
;
CDS_LIB"mstr_standard"
BODY_TYPE"PLUMBING"
HDL_TAP"TRUE";
"B \NAC \NWC"6;
"S \NAC"
BN"14"99;
%"TAP"
"1","(-6025,2975)","0","mstr_standard","I52";
;
CDS_LIB"mstr_standard"
BODY_TYPE"PLUMBING"
HDL_TAP"TRUE";
"B \NAC \NWC"6;
"S \NAC"
BN"16"101;
%"TAP"
"1","(-6025,2925)","0","mstr_standard","I53";
;
CDS_LIB"mstr_standard"
BODY_TYPE"PLUMBING"
HDL_TAP"TRUE";
"B \NAC \NWC"6;
"S \NAC"
BN"15"100;
%"TAP"
"1","(-6025,3025)","0","mstr_standard","I54";
;
CDS_LIB"mstr_standard"
BODY_TYPE"PLUMBING"
HDL_TAP"TRUE";
"B \NAC \NWC"6;
"S \NAC"
BN"17"102;
%"TAP"
"1","(-6025,3075)","0","mstr_standard","I55";
;
CDS_LIB"mstr_standard"
BODY_TYPE"PLUMBING"
HDL_TAP"TRUE";
"B \NAC \NWC"6;
"S \NAC"
BN"18"103;
%"TAP"
"1","(-6025,3125)","0","mstr_standard","I56";
;
CDS_LIB"mstr_standard"
BODY_TYPE"PLUMBING"
HDL_TAP"TRUE";
"B \NAC \NWC"6;
"S \NAC"
BN"19"104;
%"TAP"
"1","(-6025,3175)","0","mstr_standard","I57";
;
CDS_LIB"mstr_standard"
BODY_TYPE"PLUMBING"
HDL_TAP"TRUE";
"B \NAC \NWC"6;
"S \NAC"
BN"20"105;
%"TAP"
"1","(-6025,3225)","0","mstr_standard","I58";
;
CDS_LIB"mstr_standard"
BODY_TYPE"PLUMBING"
HDL_TAP"TRUE";
"B \NAC \NWC"6;
"S \NAC"
BN"21"106;
%"TAP"
"1","(-6025,3275)","0","mstr_standard","I59";
;
CDS_LIB"mstr_standard"
BODY_TYPE"PLUMBING"
HDL_TAP"TRUE";
"B \NAC \NWC"6;
"S \NAC"
BN"22"107;
%"TAP"
"1","(-6025,3375)","0","mstr_standard","I60";
;
CDS_LIB"mstr_standard"
BODY_TYPE"PLUMBING"
HDL_TAP"TRUE";
"B \NAC \NWC"6;
"S \NAC"
BN"24"109;
%"TAP"
"1","(-6025,3325)","0","mstr_standard","I61";
;
CDS_LIB"mstr_standard"
BODY_TYPE"PLUMBING"
HDL_TAP"TRUE";
"B \NAC \NWC"6;
"S \NAC"
BN"23"108;
%"TAP"
"1","(-6025,3425)","0","mstr_standard","I62";
;
CDS_LIB"mstr_standard"
BODY_TYPE"PLUMBING"
HDL_TAP"TRUE";
"B \NAC \NWC"6;
"S \NAC"
BN"25"110;
%"TAP"
"1","(-6025,3475)","0","mstr_standard","I63";
;
CDS_LIB"mstr_standard"
BODY_TYPE"PLUMBING"
HDL_TAP"TRUE";
"B \NAC \NWC"6;
"S \NAC"
BN"26"111;
%"TAP"
"1","(-6025,3525)","0","mstr_standard","I64";
;
CDS_LIB"mstr_standard"
BODY_TYPE"PLUMBING"
HDL_TAP"TRUE";
"B \NAC \NWC"6;
"S \NAC"
BN"27"112;
%"TAP"
"1","(-6025,3625)","0","mstr_standard","I65";
;
CDS_LIB"mstr_standard"
BODY_TYPE"PLUMBING"
HDL_TAP"TRUE";
"B \NAC \NWC"6;
"S \NAC"
BN"29"114;
%"TAP"
"1","(-6025,3575)","0","mstr_standard","I66";
;
CDS_LIB"mstr_standard"
BODY_TYPE"PLUMBING"
HDL_TAP"TRUE";
"B \NAC \NWC"6;
"S \NAC"
BN"28"113;
%"TAP"
"1","(-6025,3725)","0","mstr_standard","I67";
;
CDS_LIB"mstr_standard"
BODY_TYPE"PLUMBING"
HDL_TAP"TRUE";
"B \NAC \NWC"6;
"S \NAC"
BN"31"116;
%"TAP"
"1","(-6025,3675)","0","mstr_standard","I68";
;
CDS_LIB"mstr_standard"
BODY_TYPE"PLUMBING"
HDL_TAP"TRUE";
"B \NAC \NWC"6;
"S \NAC"
BN"30"115;
%"TAP"
"1","(-6025,3825)","0","mstr_standard","I69";
;
CDS_LIB"mstr_standard"
BODY_TYPE"PLUMBING"
HDL_TAP"TRUE";
"B \NAC \NWC"5;
"S \NAC"
BN"0"117;
%"TAP"
"1","(-6025,3875)","0","mstr_standard","I70";
;
CDS_LIB"mstr_standard"
BODY_TYPE"PLUMBING"
HDL_TAP"TRUE";
"B \NAC \NWC"5;
"S \NAC"
BN"1"118;
%"TAP"
"1","(-7725,3925)","2","mstr_standard","I80";
;
CDS_LIB"mstr_standard"
BODY_TYPE"PLUMBING"
HDL_TAP"TRUE";
"B \NAC \NWC"1;
"S \NAC"
BN"6"161;
%"TAP"
"1","(-7725,3975)","2","mstr_standard","I81";
;
CDS_LIB"mstr_standard"
BODY_TYPE"PLUMBING"
HDL_TAP"TRUE";
"B \NAC \NWC"1;
"S \NAC"
BN"7"175;
%"TAP"
"1","(-7725,4675)","2","mstr_standard","I82";
;
CDS_LIB"mstr_standard"
BODY_TYPE"PLUMBING"
HDL_TAP"TRUE";
"B \NAC \NWC"3;
"S \NAC"
BN"0"170;
%"TAP"
"1","(-7725,4775)","2","mstr_standard","I83";
;
CDS_LIB"mstr_standard"
BODY_TYPE"PLUMBING"
HDL_TAP"TRUE";
"B \NAC \NWC"3;
"S \NAC"
BN"2"166;
%"TAP"
"1","(-7725,4725)","2","mstr_standard","I84";
;
CDS_LIB"mstr_standard"
BODY_TYPE"PLUMBING"
HDL_TAP"TRUE";
"B \NAC \NWC"3;
"S \NAC"
BN"1"168;
%"TAP"
"1","(-7725,4875)","2","mstr_standard","I85";
;
CDS_LIB"mstr_standard"
BODY_TYPE"PLUMBING"
HDL_TAP"TRUE";
"B \NAC \NWC"3;
"S \NAC"
BN"4"164;
%"TAP"
"1","(-7725,4825)","2","mstr_standard","I86";
;
CDS_LIB"mstr_standard"
BODY_TYPE"PLUMBING"
HDL_TAP"TRUE";
"B \NAC \NWC"3;
"S \NAC"
BN"3"165;
%"TAP"
"1","(-7725,4925)","2","mstr_standard","I87";
;
CDS_LIB"mstr_standard"
BODY_TYPE"PLUMBING"
HDL_TAP"TRUE";
"B \NAC \NWC"3;
"S \NAC"
BN"5"163;
%"TAP"
"1","(-7725,4975)","2","mstr_standard","I88";
;
CDS_LIB"mstr_standard"
BODY_TYPE"PLUMBING"
HDL_TAP"TRUE";
"B \NAC \NWC"3;
"S \NAC"
BN"6"162;
%"TAP"
"1","(-7725,5075)","2","mstr_standard","I89";
;
CDS_LIB"mstr_standard"
BODY_TYPE"PLUMBING"
HDL_TAP"TRUE";
"B \NAC \NWC"2;
"S \NAC"
BN"0"171;
%"VCC_CORE"
"1","(-8500,3400)","0","mstr_symbols","I9";
;
HDL_POWER"P3V3_STBY"
CDS_LIB"mstr_symbols"
VOLTAGE"3.3"
ROOM"PVCCINFAON_CPU0_CTRL";
"A"27;
%"TAP"
"1","(-7725,5125)","2","mstr_standard","I90";
;
CDS_LIB"mstr_standard"
BODY_TYPE"PLUMBING"
HDL_TAP"TRUE";
"B \NAC \NWC"2;
"S \NAC"
BN"1"169;
%"TAP"
"1","(-7725,5175)","2","mstr_standard","I91";
;
CDS_LIB"mstr_standard"
BODY_TYPE"PLUMBING"
HDL_TAP"TRUE";
"B \NAC \NWC"2;
"S \NAC"
BN"2"167;
%"TAP"
"1","(-7725,5225)","2","mstr_standard","I92";
;
CDS_LIB"mstr_standard"
BODY_TYPE"PLUMBING"
HDL_TAP"TRUE";
"B \NAC \NWC"2;
"S \NAC"
BN"3"38;
%"TAP"
"1","(-7725,5275)","2","mstr_standard","I93";
;
CDS_LIB"mstr_standard"
BODY_TYPE"PLUMBING"
HDL_TAP"TRUE";
"B \NAC \NWC"2;
"S \NAC"
BN"4"37;
%"TAP"
"1","(-7725,5325)","2","mstr_standard","I94";
;
CDS_LIB"mstr_standard"
BODY_TYPE"PLUMBING"
HDL_TAP"TRUE";
"B \NAC \NWC"2;
"S \NAC"
BN"5"36;
%"TAP"
"1","(-7725,5375)","2","mstr_standard","I95";
;
CDS_LIB"mstr_standard"
BODY_TYPE"PLUMBING"
HDL_TAP"TRUE";
"B \NAC \NWC"2;
"S \NAC"
BN"6"35;
%"TAP"
"1","(-6025,3925)","0","mstr_standard","I96";
;
CDS_LIB"mstr_standard"
BODY_TYPE"PLUMBING"
HDL_TAP"TRUE";
"B \NAC \NWC"5;
"S \NAC"
BN"2"119;
%"TAP"
"1","(-6025,3975)","0","mstr_standard","I97";
;
CDS_LIB"mstr_standard"
BODY_TYPE"PLUMBING"
HDL_TAP"TRUE";
"B \NAC \NWC"5;
"S \NAC"
BN"3"120;
%"TAP"
"1","(-6025,4025)","0","mstr_standard","I98";
;
CDS_LIB"mstr_standard"
BODY_TYPE"PLUMBING"
HDL_TAP"TRUE";
"B \NAC \NWC"5;
"S \NAC"
BN"4"121;
%"TAP"
"1","(-6025,4075)","0","mstr_standard","I99";
;
CDS_LIB"mstr_standard"
BODY_TYPE"PLUMBING"
HDL_TAP"TRUE";
"B \NAC \NWC"5;
"S \NAC"
BN"5"122;
END.
